(kicad_pcb
	(version 20260206)
	(generator "pcbnew")
	(generator_version "10.0")
	(general
		(thickness 1.6)
		(legacy_teardrops no)
	)
	(paper "A4")
	(title_block
		(title "Bryce Canyon_SCC_16316-1_OCP.brd")
		(comment 1 "Bryce Canyon / footprints 249-254 of 1561")
	)
	(layers
		(0 "F.Cu" signal "TOP")
		(4 "In1.Cu" signal "L2GND")
		(6 "In2.Cu" signal "L3")
		(8 "In3.Cu" signal "L4VCC")
		(10 "In4.Cu" signal "L5VCC")
		(12 "In5.Cu" signal "L6")
		(14 "In6.Cu" signal "L7GND")
		(2 "B.Cu" signal "BOTTOM")
		(9 "F.Adhes" user "F.Adhesive")
		(11 "B.Adhes" user "B.Adhesive")
		(13 "F.Paste" user "Package Geometry/Pastemask Top")
		(15 "B.Paste" user "Package Geometry/Pastemask Bottom")
		(5 "F.SilkS" user "Ref Des/Silkscreen Top")
		(7 "B.SilkS" user "Ref Des/Silkscreen Bottom")
		(1 "F.Mask" user "Board Geometry/Soldermask Top")
		(3 "B.Mask" user "Board Geometry/Soldermask Bottom")
		(17 "Dwgs.User" user "User.Drawings")
		(19 "Cmts.User" user "User.Comments")
		(21 "Eco1.User" user "User.Eco1")
		(23 "Eco2.User" user "User.Eco2")
		(25 "Edge.Cuts" user "Board Geometry/Outline")
		(27 "Margin" user)
		(31 "F.CrtYd" user "Package Geometry/Place Bound Top")
		(29 "B.CrtYd" user "Package Geometry/Place Bound Bottom")
		(35 "F.Fab" user "Ref Des/Assembly Top")
		(33 "B.Fab" user "Ref Des/Assembly Bottom")
	)
	(footprint ""
		(layer "F.Cu")
		(at 142.778226 -64.375284 -90)
		(property "Reference" "C34"
			(at 0 0 270)
			(layer "F.SilkS")
			(hide yes)
			(effects
				(font
					(size 1.27 1.27)
				)
			)
		)
		(property "Value" "SCD01U16V1KX-GP"
			(at -2.8321 -1.7399 270)
			(unlocked yes)
			(layer "F.Fab")
			(hide yes)
			(effects
				(font
					(size 1.016 1.016)
					(thickness 0.1524)
				)
			)
		)
		(property "Device Type" "C0201H13"
			(at -2.8321 -3.2639 270)
			(unlocked yes)
			(layer "F.Fab")
			(hide yes)
			(effects
				(font
					(size 1.016 1.016)
					(thickness 0.1524)
				)
			)
		)
		(duplicate_pad_numbers_are_jumpers no)
		(fp_rect
			(start -0.2794 0.6477)
			(end 0.2794 -0.6477)
			(stroke
				(width 0)
				(type default)
			)
			(fill no)
			(layer "F.CrtYd")
		)
		(fp_rect
			(start -0.2794 0.6477)
			(end 0.2794 -0.6477)
			(stroke
				(width 0)
				(type default)
			)
			(fill no)
			(layer "F.Fab")
		)
		(pad "1" smd custom
			(at 0 -0.2794 270)
			(size 0.0762 0.0762)
			(layers "F.Cu" "F.Mask" "F.Paste")
			(net "PHY_IOC_TO_SCC_47_DN")
			(options
				(clearance outline)
				(anchor circle)
			)
			(primitives
				(gr_poly
					(pts
						(arc
							(start 0.1524 -0.127)
							(mid 0.137521 -0.162921)
							(end 0.1016 -0.1778)
						)
						(arc
							(start -0.1016 -0.1778)
							(mid -0.137521 -0.162921)
							(end -0.1524 -0.127)
						)
						(arc
							(start -0.1524 0.127)
							(mid -0.137521 0.162921)
							(end -0.1016 0.1778)
						)
						(arc
							(start 0.1016 0.1778)
							(mid 0.137521 0.162921)
							(end 0.1524 0.127)
						)
					)
					(width 0)
					(fill yes)
				)
			)
		)
		(pad "2" smd custom
			(at 0 0.2794 270)
			(size 0.0762 0.0762)
			(layers "F.Cu" "F.Mask" "F.Paste")
			(net "PHY_IOC_TO_SCC_C_47_DN")
			(options
				(clearance outline)
				(anchor circle)
			)
			(primitives
				(gr_poly
					(pts
						(arc
							(start 0.1524 -0.127)
							(mid 0.137521 -0.162921)
							(end 0.1016 -0.1778)
						)
						(arc
							(start -0.1016 -0.1778)
							(mid -0.137521 -0.162921)
							(end -0.1524 -0.127)
						)
						(arc
							(start -0.1524 0.127)
							(mid -0.137521 0.162921)
							(end -0.1016 0.1778)
						)
						(arc
							(start 0.1016 0.1778)
							(mid 0.137521 0.162921)
							(end 0.1524 0.127)
						)
					)
					(width 0)
					(fill yes)
				)
			)
		)
	)
	(footprint ""
		(layer "F.Cu")
		(at 176.406048 -116.146834)
		(property "Reference" "U4"
			(at 0 0 0)
			(layer "F.SilkS")
			(hide yes)
			(effects
				(font
					(size 1.27 1.27)
				)
			)
		)
		(property "Value" "TPS74801RGW-GP"
			(at -4.7244 -6.223 0)
			(unlocked yes)
			(layer "F.Fab")
			(hide yes)
			(effects
				(font
					(size 1.016 1.016)
					(thickness 0.1524)
				)
			)
		)
		(property "Device Type" "QFN20-1G3D15H40"
			(at -4.7244 -7.747 0)
			(unlocked yes)
			(layer "F.Fab")
			(hide yes)
			(effects
				(font
					(size 1.016 1.016)
					(thickness 0.1524)
				)
			)
		)
		(duplicate_pad_numbers_are_jumpers no)
		(fp_line
			(start -3.5179 -3.5179)
			(end -3.5179 -2.2479)
			(stroke
				(width 0.1524)
				(type default)
			)
			(layer "F.SilkS")
		)
		(fp_line
			(start -3.5179 2.2479)
			(end -3.5179 3.5179)
			(stroke
				(width 0.1524)
				(type default)
			)
			(layer "F.SilkS")
		)
		(fp_line
			(start -3.5179 3.5179)
			(end -2.2479 3.5179)
			(stroke
				(width 0.1524)
				(type default)
			)
			(layer "F.SilkS")
		)
		(fp_line
			(start -3.160522 1.299972)
			(end -3.922522 1.299972)
			(stroke
				(width 0.1524)
				(type default)
			)
			(layer "F.SilkS")
		)
		(fp_line
			(start -2.2479 -3.5179)
			(end -3.5179 -3.5179)
			(stroke
				(width 0.1524)
				(type default)
			)
			(layer "F.SilkS")
		)
		(fp_line
			(start -1.299972 -3.160522)
			(end -1.299972 -3.668522)
			(stroke
				(width 0.1524)
				(type default)
			)
			(layer "F.SilkS")
		)
		(fp_line
			(start 1.299972 3.160522)
			(end 1.299972 3.668522)
			(stroke
				(width 0.1524)
				(type default)
			)
			(layer "F.SilkS")
		)
		(fp_line
			(start 2.2479 3.5179)
			(end 3.5179 3.5179)
			(stroke
				(width 0.1524)
				(type default)
			)
			(layer "F.SilkS")
		)
		(fp_line
			(start 3.160522 -1.299972)
			(end 3.922522 -1.299972)
			(stroke
				(width 0.1524)
				(type default)
			)
			(layer "F.SilkS")
		)
		(fp_line
			(start 3.5179 3.5179)
			(end 3.5179 2.2479)
			(stroke
				(width 0.1524)
				(type default)
			)
			(layer "F.SilkS")
		)
		(fp_poly
			(pts
				(xy 3.5179 -3.5179) (xy 2.2479 -3.5179) (xy 3.5179 -2.2479)
			)
			(stroke
				(width 0)
				(type default)
			)
			(fill yes)
			(layer "F.SilkS")
		)
		(fp_rect
			(start -2.5019 2.5019)
			(end 2.5019 -2.5019)
			(stroke
				(width 0)
				(type default)
			)
			(fill no)
			(layer "F.CrtYd")
		)
		(fp_poly
			(pts
				(xy -3.5179 3.5179) (xy -3.5179 -3.5179) (xy 3.5179 -3.5179) (xy 3.5179 -2.5019) (xy -2.5019 -2.5019)
				(xy -2.5019 2.5019) (xy 2.5019 2.5019) (xy 2.5019 -2.49682) (xy 3.5179 -2.49682) (xy 3.5179 3.5179)
			)
			(stroke
				(width 0)
				(type default)
			)
			(fill no)
			(layer "F.CrtYd")
		)
		(fp_rect
			(start -3.5179 3.5179)
			(end 3.5179 -3.5179)
			(stroke
				(width 0)
				(type default)
			)
			(fill no)
			(layer "F.Fab")
		)
		(pad "1" smd rect
			(at 1.299972 -2.474722)
			(size 0.3556 1.0668)
			(layers "F.Cu" "F.Mask" "F.Paste")
			(net "P1V8_E_OUT")
		)
		(pad "2" smd rect
			(at 0.649986 -2.474722)
			(size 0.3556 1.0668)
			(layers "F.Cu" "F.Mask" "F.Paste")
			(net "GND")
		)
		(pad "3" smd rect
			(at 0 -2.474722)
			(size 0.3556 1.0668)
			(layers "F.Cu" "F.Mask" "F.Paste")
			(net "GND")
		)
		(pad "4" smd rect
			(at -0.649986 -2.474722)
			(size 0.3556 1.0668)
			(layers "F.Cu" "F.Mask" "F.Paste")
			(net "GND")
		)
		(pad "5" smd rect
			(at -1.299972 -2.474722)
			(size 0.3556 1.0668)
			(layers "F.Cu" "F.Mask" "F.Paste")
			(net "P3V3")
		)
		(pad "6" smd rect
			(at -2.474722 -1.299972)
			(size 1.0668 0.3556)
			(layers "F.Cu" "F.Mask" "F.Paste")
			(net "P3V3")
		)
		(pad "7" smd rect
			(at -2.474722 -0.649986)
			(size 1.0668 0.3556)
			(layers "F.Cu" "F.Mask" "F.Paste")
			(net "P3V3")
		)
		(pad "8" smd rect
			(at -2.474722 0)
			(size 1.0668 0.3556)
			(layers "F.Cu" "F.Mask" "F.Paste")
			(net "P3V3")
		)
		(pad "9" smd rect
			(at -2.474722 0.649986)
			(size 1.0668 0.3556)
			(layers "F.Cu" "F.Mask" "F.Paste")
			(net "P1V8_E_PG")
		)
		(pad "10" smd rect
			(at -2.474722 1.299972)
			(size 1.0668 0.3556)
			(layers "F.Cu" "F.Mask" "F.Paste")
			(net "P1V8_E_BIAS")
		)
		(pad "11" smd rect
			(at -1.299972 2.474722)
			(size 0.3556 1.0668)
			(layers "F.Cu" "F.Mask" "F.Paste")
			(net "P1V8_E_EN")
		)
		(pad "12" smd rect
			(at -0.649986 2.474722)
			(size 0.3556 1.0668)
			(layers "F.Cu" "F.Mask" "F.Paste")
			(net "GND")
		)
		(pad "13" smd rect
			(at 0 2.474722)
			(size 0.3556 1.0668)
			(layers "F.Cu" "F.Mask" "F.Paste")
			(net "GND")
		)
		(pad "14" smd rect
			(at 0.649986 2.474722)
			(size 0.3556 1.0668)
			(layers "F.Cu" "F.Mask" "F.Paste")
			(net "GND")
		)
		(pad "15" smd rect
			(at 1.299972 2.474722)
			(size 0.3556 1.0668)
			(layers "F.Cu" "F.Mask" "F.Paste")
			(net "P1V8_E_SS")
		)
		(pad "16" smd rect
			(at 2.474722 1.299972)
			(size 1.0668 0.3556)
			(layers "F.Cu" "F.Mask" "F.Paste")
			(net "P1V8_E_FB")
		)
		(pad "17" smd rect
			(at 2.474722 0.649986)
			(size 1.0668 0.3556)
			(layers "F.Cu" "F.Mask" "F.Paste")
			(net "GND")
		)
		(pad "18" smd rect
			(at 2.474722 0)
			(size 1.0668 0.3556)
			(layers "F.Cu" "F.Mask" "F.Paste")
			(net "P1V8_E_OUT")
		)
		(pad "19" smd rect
			(at 2.474722 -0.649986)
			(size 1.0668 0.3556)
			(layers "F.Cu" "F.Mask" "F.Paste")
			(net "P1V8_E_OUT")
		)
		(pad "20" smd rect
			(at 2.474722 -1.299972)
			(size 1.0668 0.3556)
			(layers "F.Cu" "F.Mask" "F.Paste")
			(net "P1V8_E_OUT")
		)
		(pad "21" smd rect
			(at 0 0)
			(size 3.2512 3.2512)
			(layers "F.Cu" "F.Mask" "F.Paste")
			(net "GND")
		)
	)
	(footprint ""
		(layer "F.Cu")
		(at 163.878768 -23.935944 -90)
		(property "Reference" "R173"
			(at 0 0 270)
			(layer "F.SilkS")
			(hide yes)
			(effects
				(font
					(size 1.27 1.27)
				)
			)
		)
		(property "Value" "51R2F-2-GP"
			(at 0.064008 -3.993896 270)
			(unlocked yes)
			(layer "F.Fab")
			(hide yes)
			(effects
				(font
					(size 1.016 1.016)
					(thickness 0.1524)
				)
			)
		)
		(property "Device Type" "R402H16"
			(at 0.064008 -5.517896 270)
			(unlocked yes)
			(layer "F.Fab")
			(hide yes)
			(effects
				(font
					(size 1.016 1.016)
					(thickness 0.1524)
				)
			)
		)
		(duplicate_pad_numbers_are_jumpers no)
		(fp_line
			(start -0.508 -0.9398)
			(end -0.508 0.9398)
			(stroke
				(width 0.1524)
				(type default)
			)
			(layer "F.SilkS")
		)
		(fp_line
			(start 0.508 -0.9398)
			(end -0.508 -0.9398)
			(stroke
				(width 0.1524)
				(type default)
			)
			(layer "F.SilkS")
		)
		(fp_rect
			(start -0.508 0.9398)
			(end 0.508 -0.9398)
			(stroke
				(width 0)
				(type default)
			)
			(fill no)
			(layer "F.CrtYd")
		)
		(fp_rect
			(start -0.508 0.9398)
			(end 0.508 -0.9398)
			(stroke
				(width 0)
				(type default)
			)
			(fill no)
			(layer "F.Fab")
		)
		(pad "1" smd custom
			(at 0 -0.4445 270)
			(size 0.1397 0.1397)
			(layers "F.Cu" "F.Mask" "F.Paste")
			(net "GND")
			(options
				(clearance outline)
				(anchor circle)
			)
			(primitives
				(gr_poly
					(pts
						(arc
							(start -0.1778 -0.2794)
							(mid -0.249642 -0.249642)
							(end -0.2794 -0.1778)
						)
						(arc
							(start -0.2794 0.1778)
							(mid -0.249642 0.249642)
							(end -0.1778 0.2794)
						)
						(arc
							(start 0.1778 0.2794)
							(mid 0.249642 0.249642)
							(end 0.2794 0.1778)
						)
						(arc
							(start 0.2794 -0.1778)
							(mid 0.249642 -0.249642)
							(end 0.1778 -0.2794)
						)
					)
					(width 0)
					(fill yes)
				)
			)
		)
		(pad "2" smd custom
			(at 0 0.4445 270)
			(size 0.1397 0.1397)
			(layers "F.Cu" "F.Mask" "F.Paste")
			(net "PCIE_CLK_R_N")
			(options
				(clearance outline)
				(anchor circle)
			)
			(primitives
				(gr_poly
					(pts
						(arc
							(start -0.1778 -0.2794)
							(mid -0.249642 -0.249642)
							(end -0.2794 -0.1778)
						)
						(arc
							(start -0.2794 0.1778)
							(mid -0.249642 0.249642)
							(end -0.1778 0.2794)
						)
						(arc
							(start 0.1778 0.2794)
							(mid 0.249642 0.249642)
							(end 0.2794 0.1778)
						)
						(arc
							(start 0.2794 -0.1778)
							(mid 0.249642 -0.249642)
							(end 0.1778 -0.2794)
						)
					)
					(width 0)
					(fill yes)
				)
			)
		)
	)
	(footprint ""
		(layer "F.Cu")
		(at 151.930608 -92.593414 180)
		(property "Reference" "C503"
			(at 0 0 180)
			(layer "F.SilkS")
			(hide yes)
			(effects
				(font
					(size 1.27 1.27)
				)
			)
		)
		(property "Value" "SCD1U16V2KX-3GP"
			(at 1.1811 -2.7051 180)
			(unlocked yes)
			(layer "F.Fab")
			(hide yes)
			(effects
				(font
					(size 1.016 1.016)
					(thickness 0.1524)
				)
			)
		)
		(property "Device Type" "C402H22"
			(at 1.1811 -4.2291 180)
			(unlocked yes)
			(layer "F.Fab")
			(hide yes)
			(effects
				(font
					(size 1.016 1.016)
					(thickness 0.1524)
				)
			)
		)
		(duplicate_pad_numbers_are_jumpers no)
		(fp_rect
			(start -0.4318 0.9525)
			(end 0.4318 -0.9525)
			(stroke
				(width 0)
				(type default)
			)
			(fill no)
			(layer "F.CrtYd")
		)
		(fp_rect
			(start -0.4318 0.9525)
			(end 0.4318 -0.9525)
			(stroke
				(width 0)
				(type default)
			)
			(fill no)
			(layer "F.Fab")
		)
		(pad "1" smd custom
			(at 0 -0.4445 180)
			(size 0.1524 0.1524)
			(layers "F.Cu" "F.Mask" "F.Paste")
			(net "P1V8_E")
			(options
				(clearance outline)
				(anchor circle)
			)
			(primitives
				(gr_poly
					(pts
						(arc
							(start 0.3048 -0.2032)
							(mid 0.275042 -0.275042)
							(end 0.2032 -0.3048)
						)
						(arc
							(start -0.2032 -0.3048)
							(mid -0.275042 -0.275042)
							(end -0.3048 -0.2032)
						)
						(arc
							(start -0.3048 0.2032)
							(mid -0.275042 0.275042)
							(end -0.2032 0.3048)
						)
						(arc
							(start 0.2032 0.3048)
							(mid 0.275042 0.275042)
							(end 0.3048 0.2032)
						)
					)
					(width 0)
					(fill yes)
				)
			)
		)
		(pad "2" smd custom
			(at 0 0.4445 180)
			(size 0.1524 0.1524)
			(layers "F.Cu" "F.Mask" "F.Paste")
			(net "GND")
			(options
				(clearance outline)
				(anchor circle)
			)
			(primitives
				(gr_poly
					(pts
						(arc
							(start 0.3048 -0.2032)
							(mid 0.275042 -0.275042)
							(end 0.2032 -0.3048)
						)
						(arc
							(start -0.2032 -0.3048)
							(mid -0.275042 -0.275042)
							(end -0.3048 -0.2032)
						)
						(arc
							(start -0.3048 0.2032)
							(mid -0.275042 0.275042)
							(end -0.2032 0.3048)
						)
						(arc
							(start 0.2032 0.3048)
							(mid 0.275042 0.275042)
							(end 0.3048 0.2032)
						)
					)
					(width 0)
					(fill yes)
				)
			)
		)
	)
	(footprint ""
		(layer "F.Cu")
		(at 152.253442 -90.609166 -90)
		(property "Reference" "R290"
			(at 0 0 270)
			(layer "F.SilkS")
			(hide yes)
			(effects
				(font
					(size 1.27 1.27)
				)
			)
		)
		(property "Value" "0R2J-2-GP"
			(at 0.064008 -3.993896 270)
			(unlocked yes)
			(layer "F.Fab")
			(hide yes)
			(effects
				(font
					(size 1.016 1.016)
					(thickness 0.1524)
				)
			)
		)
		(property "Device Type" "R402H16"
			(at 0.064008 -5.517896 270)
			(unlocked yes)
			(layer "F.Fab")
			(hide yes)
			(effects
				(font
					(size 1.016 1.016)
					(thickness 0.1524)
				)
			)
		)
		(duplicate_pad_numbers_are_jumpers no)
		(fp_line
			(start -0.508 -0.9398)
			(end -0.508 0.9398)
			(stroke
				(width 0.1524)
				(type default)
			)
			(layer "F.SilkS")
		)
		(fp_line
			(start 0.508 -0.9398)
			(end -0.508 -0.9398)
			(stroke
				(width 0.1524)
				(type default)
			)
			(layer "F.SilkS")
		)
		(fp_rect
			(start -0.508 0.9398)
			(end 0.508 -0.9398)
			(stroke
				(width 0)
				(type default)
			)
			(fill no)
			(layer "F.CrtYd")
		)
		(fp_rect
			(start -0.508 0.9398)
			(end 0.508 -0.9398)
			(stroke
				(width 0)
				(type default)
			)
			(fill no)
			(layer "F.Fab")
		)
		(pad "1" smd custom
			(at 0 -0.4445 270)
			(size 0.1397 0.1397)
			(layers "F.Cu" "F.Mask" "F.Paste")
			(net "SAS_SMART_R_RX")
			(options
				(clearance outline)
				(anchor circle)
			)
			(primitives
				(gr_poly
					(pts
						(arc
							(start -0.1778 -0.2794)
							(mid -0.249642 -0.249642)
							(end -0.2794 -0.1778)
						)
						(arc
							(start -0.2794 0.1778)
							(mid -0.249642 0.249642)
							(end -0.1778 0.2794)
						)
						(arc
							(start 0.1778 0.2794)
							(mid 0.249642 0.249642)
							(end 0.2794 0.1778)
						)
						(arc
							(start 0.2794 -0.1778)
							(mid 0.249642 -0.249642)
							(end 0.1778 -0.2794)
						)
					)
					(width 0)
					(fill yes)
				)
			)
		)
		(pad "2" smd custom
			(at 0 0.4445 270)
			(size 0.1397 0.1397)
			(layers "F.Cu" "F.Mask" "F.Paste")
			(net "SAS_SMART_RX")
			(options
				(clearance outline)
				(anchor circle)
			)
			(primitives
				(gr_poly
					(pts
						(arc
							(start -0.1778 -0.2794)
							(mid -0.249642 -0.249642)
							(end -0.2794 -0.1778)
						)
						(arc
							(start -0.2794 0.1778)
							(mid -0.249642 0.249642)
							(end -0.1778 0.2794)
						)
						(arc
							(start 0.1778 0.2794)
							(mid 0.249642 0.249642)
							(end 0.2794 0.1778)
						)
						(arc
							(start 0.2794 -0.1778)
							(mid 0.249642 -0.249642)
							(end 0.1778 -0.2794)
						)
					)
					(width 0)
					(fill yes)
				)
			)
		)
	)
	(footprint ""
		(layer "F.Cu")
		(at 145.68678 -117.34292 180)
		(property "Reference" "R378"
			(at 0 0 180)
			(layer "F.SilkS")
			(hide yes)
			(effects
				(font
					(size 1.27 1.27)
				)
			)
		)
		(property "Value" "1K5R2F-2-GP"
			(at 0.064008 -3.993896 180)
			(unlocked yes)
			(layer "F.Fab")
			(hide yes)
			(effects
				(font
					(size 1.016 1.016)
					(thickness 0.1524)
				)
			)
		)
		(property "Device Type" "R402H16"
			(at 0.064008 -5.517896 180)
			(unlocked yes)
			(layer "F.Fab")
			(hide yes)
			(effects
				(font
					(size 1.016 1.016)
					(thickness 0.1524)
				)
			)
		)
		(duplicate_pad_numbers_are_jumpers no)
		(fp_line
			(start 0.508 -0.9398)
			(end -0.508 -0.9398)
			(stroke
				(width 0.1524)
				(type default)
			)
			(layer "F.SilkS")
		)
		(fp_line
			(start -0.508 -0.9398)
			(end -0.508 0.9398)
			(stroke
				(width 0.1524)
				(type default)
			)
			(layer "F.SilkS")
		)
		(fp_rect
			(start -0.508 0.9398)
			(end 0.508 -0.9398)
			(stroke
				(width 0)
				(type default)
			)
			(fill no)
			(layer "F.CrtYd")
		)
		(fp_rect
			(start -0.508 0.9398)
			(end 0.508 -0.9398)
			(stroke
				(width 0)
				(type default)
			)
			(fill no)
			(layer "F.Fab")
		)
		(pad "1" smd custom
			(at 0 -0.4445 180)
			(size 0.1397 0.1397)
			(layers "F.Cu" "F.Mask" "F.Paste")
			(net "P1V5_E_LL")
			(options
				(clearance outline)
				(anchor circle)
			)
			(primitives
				(gr_poly
					(pts
						(arc
							(start -0.1778 -0.2794)
							(mid -0.249642 -0.249642)
							(end -0.2794 -0.1778)
						)
						(arc
							(start -0.2794 0.1778)
							(mid -0.249642 0.249642)
							(end -0.1778 0.2794)
						)
						(arc
							(start 0.1778 0.2794)
							(mid 0.249642 0.249642)
							(end 0.2794 0.1778)
						)
						(arc
							(start 0.2794 -0.1778)
							(mid 0.249642 -0.249642)
							(end 0.1778 -0.2794)
						)
					)
					(width 0)
					(fill yes)
				)
			)
		)
		(pad "2" smd custom
			(at 0 0.4445 180)
			(size 0.1397 0.1397)
			(layers "F.Cu" "F.Mask" "F.Paste")
			(net "P1V5_E_LL_R")
			(options
				(clearance outline)
				(anchor circle)
			)
			(primitives
				(gr_poly
					(pts
						(arc
							(start -0.1778 -0.2794)
							(mid -0.249642 -0.249642)
							(end -0.2794 -0.1778)
						)
						(arc
							(start -0.2794 0.1778)
							(mid -0.249642 0.249642)
							(end -0.1778 0.2794)
						)
						(arc
							(start 0.1778 0.2794)
							(mid 0.249642 0.249642)
							(end 0.2794 0.1778)
						)
						(arc
							(start 0.2794 -0.1778)
							(mid 0.249642 -0.249642)
							(end 0.1778 -0.2794)
						)
					)
					(width 0)
					(fill yes)
				)
			)
		)
	)
)
